(kicad_pcb
	(version 20260206)
	(generator "pcbnew")
	(generator_version "10.0")
	(general
		(thickness 1.6)
		(legacy_teardrops no)
	)
	(paper "A4")
	(title_block
		(title "baseboard — 13948-1b.1110WZS1818.brd")
		(comment 1 "Honey Badger (Wiwynn) / footprints 1465-1471 of 2523")
	)
	(layers
		(0 "F.Cu" signal "TOP")
		(4 "In1.Cu" signal "L2GND")
		(6 "In2.Cu" signal "L3")
		(8 "In3.Cu" signal "L4VCC")
		(10 "In4.Cu" signal "L5VCC")
		(12 "In5.Cu" signal "L6")
		(14 "In6.Cu" signal "L7GND")
		(2 "B.Cu" signal "BOTTOM")
		(9 "F.Adhes" user "F.Adhesive")
		(11 "B.Adhes" user "B.Adhesive")
		(13 "F.Paste" user "Package Geometry/Pastemask Top")
		(15 "B.Paste" user "Package Geometry/Pastemask Bottom")
		(5 "F.SilkS" user "Ref Des/Silkscreen Top")
		(7 "B.SilkS" user "Ref Des/Silkscreen Bottom")
		(1 "F.Mask" user "Board Geometry/Soldermask Top")
		(3 "B.Mask" user "Board Geometry/Soldermask Bottom")
		(17 "Dwgs.User" user "User.Drawings")
		(19 "Cmts.User" user "User.Comments")
		(21 "Eco1.User" user "User.Eco1")
		(23 "Eco2.User" user "User.Eco2")
		(25 "Edge.Cuts" user "Board Geometry/Outline")
		(27 "Margin" user)
		(31 "F.CrtYd" user "Package Geometry/Place Bound Top")
		(29 "B.CrtYd" user "Package Geometry/Place Bound Bottom")
		(35 "F.Fab" user "Ref Des/Assembly Top")
		(33 "B.Fab" user "Ref Des/Assembly Bottom")
	)
	(footprint ""
		(layer "F.Cu")
		(at 152.019 -53.213 -90)
		(property "Reference" "SR690"
			(at 0 0 270)
			(layer "F.SilkS")
			(hide yes)
			(effects
				(font
					(size 1.27 1.27)
				)
			)
		)
		(property "Value" "10KR2F-2-GP"
			(at 0.064008 -3.993896 270)
			(unlocked yes)
			(layer "F.Fab")
			(hide yes)
			(effects
				(font
					(size 1.016 1.016)
					(thickness 0.1524)
				)
			)
		)
		(property "Device Type" "R402H16"
			(at 0.064008 -5.517896 270)
			(unlocked yes)
			(layer "F.Fab")
			(hide yes)
			(effects
				(font
					(size 1.016 1.016)
					(thickness 0.1524)
				)
			)
		)
		(duplicate_pad_numbers_are_jumpers no)
		(fp_line
			(start -0.508 -0.9398)
			(end -0.508 0.9398)
			(stroke
				(width 0.1524)
				(type default)
			)
			(layer "F.SilkS")
		)
		(fp_line
			(start 0.508 -0.9398)
			(end -0.508 -0.9398)
			(stroke
				(width 0.1524)
				(type default)
			)
			(layer "F.SilkS")
		)
		(fp_rect
			(start -0.508 0.9398)
			(end 0.508 -0.9398)
			(stroke
				(width 0)
				(type default)
			)
			(fill no)
			(layer "F.CrtYd")
		)
		(fp_rect
			(start -0.508 0.9398)
			(end 0.508 -0.9398)
			(stroke
				(width 0)
				(type default)
			)
			(fill no)
			(layer "F.Fab")
		)
		(pad "1" smd custom
			(at 0 -0.4445 270)
			(size 0.1397 0.1397)
			(layers "F.Cu" "F.Mask" "F.Paste")
			(net "P1V8_C")
			(options
				(clearance outline)
				(anchor circle)
			)
			(primitives
				(gr_poly
					(pts
						(arc
							(start -0.1778 -0.2794)
							(mid -0.249642 -0.249642)
							(end -0.2794 -0.1778)
						)
						(arc
							(start -0.2794 0.1778)
							(mid -0.249642 0.249642)
							(end -0.1778 0.2794)
						)
						(arc
							(start 0.1778 0.2794)
							(mid 0.249642 0.249642)
							(end 0.2794 0.1778)
						)
						(arc
							(start 0.2794 -0.1778)
							(mid 0.249642 -0.249642)
							(end 0.1778 -0.2794)
						)
					)
					(width 0)
					(fill yes)
				)
			)
		)
		(pad "2" smd custom
			(at 0 0.4445 270)
			(size 0.1397 0.1397)
			(layers "F.Cu" "F.Mask" "F.Paste")
			(net "XM_ADDR_4")
			(options
				(clearance outline)
				(anchor circle)
			)
			(primitives
				(gr_poly
					(pts
						(arc
							(start -0.1778 -0.2794)
							(mid -0.249642 -0.249642)
							(end -0.2794 -0.1778)
						)
						(arc
							(start -0.2794 0.1778)
							(mid -0.249642 0.249642)
							(end -0.1778 0.2794)
						)
						(arc
							(start 0.1778 0.2794)
							(mid 0.249642 0.249642)
							(end 0.2794 0.1778)
						)
						(arc
							(start 0.2794 -0.1778)
							(mid 0.249642 -0.249642)
							(end 0.1778 -0.2794)
						)
					)
					(width 0)
					(fill yes)
				)
			)
		)
	)
	(footprint ""
		(layer "F.Cu")
		(at 342.265 -106.68 90)
		(property "Reference" "PC10"
			(at 0 0 90)
			(layer "F.SilkS")
			(hide yes)
			(effects
				(font
					(size 1.27 1.27)
				)
			)
		)
		(property "Value" "SCD1U50V3KX-GP"
			(at 0 -2.8194 90)
			(unlocked yes)
			(layer "F.Fab")
			(hide yes)
			(effects
				(font
					(size 1.016 1.016)
					(thickness 0.1524)
				)
			)
		)
		(property "Device Type" "C603H36"
			(at 0 -4.3434 90)
			(unlocked yes)
			(layer "F.Fab")
			(hide yes)
			(effects
				(font
					(size 1.016 1.016)
					(thickness 0.1524)
				)
			)
		)
		(duplicate_pad_numbers_are_jumpers no)
		(fp_line
			(start 0.508 0)
			(end -0.508 0)
			(stroke
				(width 0.2032)
				(type default)
			)
			(layer "F.SilkS")
		)
		(fp_rect
			(start -0.5842 1.3335)
			(end 0.5842 -1.3335)
			(stroke
				(width 0)
				(type default)
			)
			(fill no)
			(layer "F.CrtYd")
		)
		(fp_rect
			(start -0.5842 1.3335)
			(end 0.5842 -1.3335)
			(stroke
				(width 0)
				(type default)
			)
			(fill no)
			(layer "F.Fab")
		)
		(pad "1" smd custom
			(at 0 -0.762 90)
			(size 0.2159 0.2159)
			(layers "F.Cu" "F.Mask" "F.Paste")
			(net "P5V_STBY_SW")
			(options
				(clearance outline)
				(anchor circle)
			)
			(primitives
				(gr_poly
					(pts
						(arc
							(start -0.3302 -0.4318)
							(mid -0.402042 -0.402042)
							(end -0.4318 -0.3302)
						)
						(arc
							(start -0.4318 0.3302)
							(mid -0.402042 0.402042)
							(end -0.3302 0.4318)
						)
						(arc
							(start 0.3302 0.4318)
							(mid 0.402042 0.402042)
							(end 0.4318 0.3302)
						)
						(arc
							(start 0.4318 -0.3302)
							(mid 0.402042 -0.402042)
							(end 0.3302 -0.4318)
						)
					)
					(width 0)
					(fill yes)
				)
			)
		)
		(pad "2" smd custom
			(at 0 0.762 90)
			(size 0.2159 0.2159)
			(layers "F.Cu" "F.Mask" "F.Paste")
			(net "P5V_STBY_VBST_RR")
			(options
				(clearance outline)
				(anchor circle)
			)
			(primitives
				(gr_poly
					(pts
						(arc
							(start -0.3302 -0.4318)
							(mid -0.402042 -0.402042)
							(end -0.4318 -0.3302)
						)
						(arc
							(start -0.4318 0.3302)
							(mid -0.402042 0.402042)
							(end -0.3302 0.4318)
						)
						(arc
							(start 0.3302 0.4318)
							(mid 0.402042 0.402042)
							(end 0.4318 0.3302)
						)
						(arc
							(start 0.4318 -0.3302)
							(mid 0.402042 -0.402042)
							(end 0.3302 -0.4318)
						)
					)
					(width 0)
					(fill yes)
				)
			)
		)
	)
	(footprint ""
		(layer "F.Cu")
		(at 304.717958 -58.928 180)
		(property "Reference" "C288"
			(at 0 0 180)
			(layer "F.SilkS")
			(hide yes)
			(effects
				(font
					(size 1.27 1.27)
				)
			)
		)
		(property "Value" "SCD1U25V2KX-2-GP"
			(at 1.1811 -2.7051 180)
			(unlocked yes)
			(layer "F.Fab")
			(hide yes)
			(effects
				(font
					(size 1.016 1.016)
					(thickness 0.1524)
				)
			)
		)
		(property "Device Type" "C402H22"
			(at 1.1811 -4.2291 180)
			(unlocked yes)
			(layer "F.Fab")
			(hide yes)
			(effects
				(font
					(size 1.016 1.016)
					(thickness 0.1524)
				)
			)
		)
		(duplicate_pad_numbers_are_jumpers no)
		(fp_rect
			(start -0.4318 0.9525)
			(end 0.4318 -0.9525)
			(stroke
				(width 0)
				(type default)
			)
			(fill no)
			(layer "F.CrtYd")
		)
		(fp_rect
			(start -0.4318 0.9525)
			(end 0.4318 -0.9525)
			(stroke
				(width 0)
				(type default)
			)
			(fill no)
			(layer "F.Fab")
		)
		(pad "1" smd custom
			(at 0 -0.4445 180)
			(size 0.1524 0.1524)
			(layers "F.Cu" "F.Mask" "F.Paste")
			(net "P3V3")
			(options
				(clearance outline)
				(anchor circle)
			)
			(primitives
				(gr_poly
					(pts
						(arc
							(start 0.3048 -0.2032)
							(mid 0.275042 -0.275042)
							(end 0.2032 -0.3048)
						)
						(arc
							(start -0.2032 -0.3048)
							(mid -0.275042 -0.275042)
							(end -0.3048 -0.2032)
						)
						(arc
							(start -0.3048 0.2032)
							(mid -0.275042 0.275042)
							(end -0.2032 0.3048)
						)
						(arc
							(start 0.2032 0.3048)
							(mid 0.275042 0.275042)
							(end 0.3048 0.2032)
						)
					)
					(width 0)
					(fill yes)
				)
			)
		)
		(pad "2" smd custom
			(at 0 0.4445 180)
			(size 0.1524 0.1524)
			(layers "F.Cu" "F.Mask" "F.Paste")
			(net "GND")
			(options
				(clearance outline)
				(anchor circle)
			)
			(primitives
				(gr_poly
					(pts
						(arc
							(start 0.3048 -0.2032)
							(mid 0.275042 -0.275042)
							(end 0.2032 -0.3048)
						)
						(arc
							(start -0.2032 -0.3048)
							(mid -0.275042 -0.275042)
							(end -0.3048 -0.2032)
						)
						(arc
							(start -0.3048 0.2032)
							(mid -0.275042 0.275042)
							(end -0.2032 0.3048)
						)
						(arc
							(start 0.2032 0.3048)
							(mid 0.275042 0.275042)
							(end 0.3048 0.2032)
						)
					)
					(width 0)
					(fill yes)
				)
			)
		)
	)
	(footprint ""
		(layer "F.Cu")
		(at 184.903872 -193.289936)
		(property "Reference" "C248"
			(at 0 0 0)
			(layer "F.SilkS")
			(hide yes)
			(effects
				(font
					(size 1.27 1.27)
				)
			)
		)
		(property "Value" "SC220P50V3JN-GP"
			(at 0 -2.8194 0)
			(unlocked yes)
			(layer "F.Fab")
			(hide yes)
			(effects
				(font
					(size 1.016 1.016)
					(thickness 0.1524)
				)
			)
		)
		(property "Device Type" "C603H36"
			(at 0 -4.3434 0)
			(unlocked yes)
			(layer "F.Fab")
			(hide yes)
			(effects
				(font
					(size 1.016 1.016)
					(thickness 0.1524)
				)
			)
		)
		(duplicate_pad_numbers_are_jumpers no)
		(fp_line
			(start 0.508 0)
			(end -0.508 0)
			(stroke
				(width 0.2032)
				(type default)
			)
			(layer "F.SilkS")
		)
		(fp_rect
			(start -0.5842 1.3335)
			(end 0.5842 -1.3335)
			(stroke
				(width 0)
				(type default)
			)
			(fill no)
			(layer "F.CrtYd")
		)
		(fp_rect
			(start -0.5842 1.3335)
			(end 0.5842 -1.3335)
			(stroke
				(width 0)
				(type default)
			)
			(fill no)
			(layer "F.Fab")
		)
		(pad "1" smd custom
			(at 0 -0.762)
			(size 0.2159 0.2159)
			(layers "F.Cu" "F.Mask" "F.Paste")
			(net "SAS_I2C_C_BUF_SDA")
			(options
				(clearance outline)
				(anchor circle)
			)
			(primitives
				(gr_poly
					(pts
						(arc
							(start -0.3302 -0.4318)
							(mid -0.402042 -0.402042)
							(end -0.4318 -0.3302)
						)
						(arc
							(start -0.4318 0.3302)
							(mid -0.402042 0.402042)
							(end -0.3302 0.4318)
						)
						(arc
							(start 0.3302 0.4318)
							(mid 0.402042 0.402042)
							(end 0.4318 0.3302)
						)
						(arc
							(start 0.4318 -0.3302)
							(mid 0.402042 -0.402042)
							(end 0.3302 -0.4318)
						)
					)
					(width 0)
					(fill yes)
				)
			)
		)
		(pad "2" smd custom
			(at 0 0.762)
			(size 0.2159 0.2159)
			(layers "F.Cu" "F.Mask" "F.Paste")
			(net "GND")
			(options
				(clearance outline)
				(anchor circle)
			)
			(primitives
				(gr_poly
					(pts
						(arc
							(start -0.3302 -0.4318)
							(mid -0.402042 -0.402042)
							(end -0.4318 -0.3302)
						)
						(arc
							(start -0.4318 0.3302)
							(mid -0.402042 0.402042)
							(end -0.3302 0.4318)
						)
						(arc
							(start 0.3302 0.4318)
							(mid 0.402042 0.402042)
							(end 0.4318 0.3302)
						)
						(arc
							(start 0.4318 -0.3302)
							(mid 0.402042 -0.402042)
							(end 0.3302 -0.4318)
						)
					)
					(width 0)
					(fill yes)
				)
			)
		)
	)
	(footprint ""
		(layer "F.Cu")
		(at 333.375 -211.455 180)
		(property "Reference" "R208"
			(at 0 0 180)
			(layer "F.SilkS")
			(hide yes)
			(effects
				(font
					(size 1.27 1.27)
				)
			)
		)
		(property "Value" "0R2J-2-GP"
			(at 0.064008 -3.993896 180)
			(unlocked yes)
			(layer "F.Fab")
			(hide yes)
			(effects
				(font
					(size 1.016 1.016)
					(thickness 0.1524)
				)
			)
		)
		(property "Device Type" "R402H16"
			(at 0.064008 -5.517896 180)
			(unlocked yes)
			(layer "F.Fab")
			(hide yes)
			(effects
				(font
					(size 1.016 1.016)
					(thickness 0.1524)
				)
			)
		)
		(duplicate_pad_numbers_are_jumpers no)
		(fp_line
			(start 0.508 -0.9398)
			(end -0.508 -0.9398)
			(stroke
				(width 0.1524)
				(type default)
			)
			(layer "F.SilkS")
		)
		(fp_line
			(start -0.508 -0.9398)
			(end -0.508 0.9398)
			(stroke
				(width 0.1524)
				(type default)
			)
			(layer "F.SilkS")
		)
		(fp_rect
			(start -0.508 0.9398)
			(end 0.508 -0.9398)
			(stroke
				(width 0)
				(type default)
			)
			(fill no)
			(layer "F.CrtYd")
		)
		(fp_rect
			(start -0.508 0.9398)
			(end 0.508 -0.9398)
			(stroke
				(width 0)
				(type default)
			)
			(fill no)
			(layer "F.Fab")
		)
		(pad "1" smd custom
			(at 0 -0.4445 180)
			(size 0.1397 0.1397)
			(layers "F.Cu" "F.Mask" "F.Paste")
			(net "EEPROM_SCL")
			(options
				(clearance outline)
				(anchor circle)
			)
			(primitives
				(gr_poly
					(pts
						(arc
							(start -0.1778 -0.2794)
							(mid -0.249642 -0.249642)
							(end -0.2794 -0.1778)
						)
						(arc
							(start -0.2794 0.1778)
							(mid -0.249642 0.249642)
							(end -0.1778 0.2794)
						)
						(arc
							(start 0.1778 0.2794)
							(mid 0.249642 0.249642)
							(end 0.2794 0.1778)
						)
						(arc
							(start 0.2794 -0.1778)
							(mid 0.249642 -0.249642)
							(end 0.1778 -0.2794)
						)
					)
					(width 0)
					(fill yes)
				)
			)
		)
		(pad "2" smd custom
			(at 0 0.4445 180)
			(size 0.1397 0.1397)
			(layers "F.Cu" "F.Mask" "F.Paste")
			(net "BMC_I2C_A_SCL")
			(options
				(clearance outline)
				(anchor circle)
			)
			(primitives
				(gr_poly
					(pts
						(arc
							(start -0.1778 -0.2794)
							(mid -0.249642 -0.249642)
							(end -0.2794 -0.1778)
						)
						(arc
							(start -0.2794 0.1778)
							(mid -0.249642 0.249642)
							(end -0.1778 0.2794)
						)
						(arc
							(start 0.1778 0.2794)
							(mid 0.249642 0.249642)
							(end 0.2794 0.1778)
						)
						(arc
							(start 0.2794 -0.1778)
							(mid 0.249642 -0.249642)
							(end 0.1778 -0.2794)
						)
					)
					(width 0)
					(fill yes)
				)
			)
		)
	)
	(footprint ""
		(layer "F.Cu")
		(at 184.404 -226.822)
		(property "Reference" "R1581"
			(at 0 0 0)
			(layer "F.SilkS")
			(hide yes)
			(effects
				(font
					(size 1.27 1.27)
				)
			)
		)
		(property "Value" "33R2F-3-GP"
			(at 0.064008 -3.993896 0)
			(unlocked yes)
			(layer "F.Fab")
			(hide yes)
			(effects
				(font
					(size 1.016 1.016)
					(thickness 0.1524)
				)
			)
		)
		(property "Device Type" "R402H16"
			(at 0.064008 -5.517896 0)
			(unlocked yes)
			(layer "F.Fab")
			(hide yes)
			(effects
				(font
					(size 1.016 1.016)
					(thickness 0.1524)
				)
			)
		)
		(duplicate_pad_numbers_are_jumpers no)
		(fp_line
			(start -0.508 -0.9398)
			(end -0.508 0.9398)
			(stroke
				(width 0.1524)
				(type default)
			)
			(layer "F.SilkS")
		)
		(fp_line
			(start 0.508 -0.9398)
			(end -0.508 -0.9398)
			(stroke
				(width 0.1524)
				(type default)
			)
			(layer "F.SilkS")
		)
		(fp_rect
			(start -0.508 0.9398)
			(end 0.508 -0.9398)
			(stroke
				(width 0)
				(type default)
			)
			(fill no)
			(layer "F.CrtYd")
		)
		(fp_rect
			(start -0.508 0.9398)
			(end 0.508 -0.9398)
			(stroke
				(width 0)
				(type default)
			)
			(fill no)
			(layer "F.Fab")
		)
		(pad "1" smd custom
			(at 0 -0.4445)
			(size 0.1397 0.1397)
			(layers "F.Cu" "F.Mask" "F.Paste")
			(net "FP_PWRBTN")
			(options
				(clearance outline)
				(anchor circle)
			)
			(primitives
				(gr_poly
					(pts
						(arc
							(start -0.1778 -0.2794)
							(mid -0.249642 -0.249642)
							(end -0.2794 -0.1778)
						)
						(arc
							(start -0.2794 0.1778)
							(mid -0.249642 0.249642)
							(end -0.1778 0.2794)
						)
						(arc
							(start 0.1778 0.2794)
							(mid 0.249642 0.249642)
							(end 0.2794 0.1778)
						)
						(arc
							(start 0.2794 -0.1778)
							(mid 0.249642 -0.249642)
							(end 0.1778 -0.2794)
						)
					)
					(width 0)
					(fill yes)
				)
			)
		)
		(pad "2" smd custom
			(at 0 0.4445)
			(size 0.1397 0.1397)
			(layers "F.Cu" "F.Mask" "F.Paste")
			(net "FP_PWRBTN_R")
			(options
				(clearance outline)
				(anchor circle)
			)
			(primitives
				(gr_poly
					(pts
						(arc
							(start -0.1778 -0.2794)
							(mid -0.249642 -0.249642)
							(end -0.2794 -0.1778)
						)
						(arc
							(start -0.2794 0.1778)
							(mid -0.249642 0.249642)
							(end -0.1778 0.2794)
						)
						(arc
							(start 0.1778 0.2794)
							(mid 0.249642 0.249642)
							(end 0.2794 0.1778)
						)
						(arc
							(start 0.2794 -0.1778)
							(mid 0.249642 -0.249642)
							(end 0.1778 -0.2794)
						)
					)
					(width 0)
					(fill yes)
				)
			)
		)
	)
	(footprint ""
		(layer "F.Cu")
		(at 274.32 -41.148)
		(property "Reference" "PC42"
			(at 0 0 0)
			(layer "F.SilkS")
			(hide yes)
			(effects
				(font
					(size 1.27 1.27)
				)
			)
		)
		(property "Value" "SC22U25V5MX-GP"
			(at -0.0762 -6.1214 0)
			(unlocked yes)
			(layer "F.Fab")
			(hide yes)
			(effects
				(font
					(size 1.016 1.016)
					(thickness 0.1524)
				)
			)
		)
		(property "Device Type" "C805H58"
			(at -0.0762 -8.1534 0)
			(unlocked yes)
			(layer "F.Fab")
			(hide yes)
			(effects
				(font
					(size 1.016 1.016)
					(thickness 0.1524)
				)
			)
		)
		(duplicate_pad_numbers_are_jumpers no)
		(fp_line
			(start 0.635 0)
			(end -0.635 0)
			(stroke
				(width 0.508)
				(type default)
			)
			(layer "F.SilkS")
		)
		(fp_rect
			(start -0.9652 1.778)
			(end 0.9652 -1.778)
			(stroke
				(width 0)
				(type default)
			)
			(fill no)
			(layer "F.CrtYd")
		)
		(fp_poly
			(pts
				(xy -0.9652 -1.778) (xy 0.9652 -1.778) (xy 0.9652 1.778) (xy -0.9652 1.778)
			)
			(stroke
				(width 0)
				(type default)
			)
			(fill no)
			(layer "F.Fab")
		)
		(pad "1" smd rect
			(at 0 -0.9652)
			(size 1.397 1.143)
			(layers "F.Cu" "F.Mask" "F.Paste")
			(net "P1V8_STBY_VIN")
		)
		(pad "2" smd rect
			(at 0 0.9652)
			(size 1.397 1.143)
			(layers "F.Cu" "F.Mask" "F.Paste")
			(net "GND")
		)
	)
)
